FILE_TYPE = MULTI_PHYS_TABLE;

PART '74CBTLV3126PW'

{========================================================================================}
:VALUE           | PART_TYPE | MATERIAL | PART_NUMBER       = STANDARD    | LIFECYCLE      | PART_NUMBER       | JEDEC_TYPE | DESCRIPTION                                | MANUFTR | MANUF_PN        | RD_CMPLS_LVL | CMPLS_LVL | FROM_PJ       | CLASS | DIP_SMD | DATA                  | EE_CHECK_LIST | FP_ECN           | PSL | CREATOR | STATUS | CREATEDAY  ;
{========================================================================================}
 '74CBTLV3126PW' | 'SMLF'    | 'IC'     | 'AL003126K08'(!)  = ''          | ''             | 'AL003126K08'     |'TSSOP14'| 'IC OTHER(14P) 74CBTLV3126PW(TSSOP)'       | 'NXP'   | '74CBTLV3126PW' | 'EU(V1)'     | ''        | 'S4L-CHARLES' | 'IC'  | ''      | 'NXP_74CBTLV3126.pdf' | ''            | ''               | ''  | ''      | ''     | '20130102'
 '74CBTLV3126PW' | 'SMLF'    | 'EMPTY'  | 'AL003126K08'(!)  = ''          | ''             | 'AL003126K08'     |'TSSOP14'| 'IC OTHER(14P) 74CBTLV3126PW(TSSOP)'       | 'NXP'   | '74CBTLV3126PW' | 'EU(V1)'     | ''        | 'S4L-CHARLES' | 'IC'  | ''      | 'NXP_74CBTLV3126.pdf' | ''            | ''               | ''  | ''      | ''     | '20130102'
 '74CBTLV3126PW' | 'SMLF'    | 'IC'     | 'AL003126K08SEL1'(!) = ''               | ''               | 'AL003126K08SEL1' |'TSSOP14'| 'IC OTHER(14P) 74CBTLV3126PW(TSSOP)SELASN' | 'NXP'   | '74CBTLV3126PW' | 'EU(V1)'     | ''        | 'S4L-CHARLES' | 'IC'  | ''      | 'NXP_74CBTLV3126.pdf' | ''            | 'SEL_15QPN.xlsx' | ''  | ''      | ''     | '20230719'
 '74CBTLV3126PW' | 'SMLF'    | 'EMPTY'  | 'AL003126K08SEL1'(!) = ''               | ''               | 'AL003126K08SEL1' |'TSSOP14'| 'IC OTHER(14P) 74CBTLV3126PW(TSSOP)SELASN' | 'NXP'   | '74CBTLV3126PW' | 'EU(V1)'     | ''        | 'S4L-CHARLES' | 'IC'  | ''      | 'NXP_74CBTLV3126.pdf' | ''            | 'SEL_15QPN.xlsx' | ''  | ''      | ''     | '20230719'

END_PART

END.

